# S9S_MB_2U (Grand Teton) — schematic netlist excerpt (pin names and nets, part order shuffled) for the footprints in the layout excerpt that follows; sources: Cadence DE-HDL packaged netlist, KiCad conversion of 03242023_DA0F0TMBIJ0_F0T_Motherboard_J_brd_V01_OCP.brd

PU73  RS53319LR  IC  pkg QFN21_4X3  page 262
  BST  = SW_P1V05_PCH_AUX_BST
  AGND  = GND
  CS  = P1V05_PCH_AUX_CS
  MODE  = P1V05_PCH_AUX_MODE
  REF  = P1V05_PCH_AUX_REF
  RTN  = SH_P1V05_PCH_AUX_N
  FB  = P1V05_PCH_AUX_FB
  EN  = FM_P1V05_PCH_AUX_R_EN
  PGOOD  = PWRGD_P1V05_PCH_AUX_R
  VIN1  = SW_P12V_AUX_P1V05_PCH_AUX_FLT
  PGND  = GND
  VCC  = P1V05_PCH_AUX_VCC
  SW  = SW_P1V05_PCH_AUX_SW
  VIN2  = SW_P12V_AUX_P1V05_PCH_AUX_FLT

C2271  Q_CAP  1000PF 50V 5% EMPTY  pkg 0402  page 145 : A = GPU_3V3IO_RSVD1_ISO ; B = GND

(kicad_pcb
	(version 20260206)
	(generator "pcbnew")
	(generator_version "10.0")
	(general
		(thickness 1.6)
		(legacy_teardrops no)
	)
	(paper "A4")
	(title_block
		(title "03242023_DA0F0TMBIJ0_F0T_Motherboard_J_brd_V01_OCP.brd")
		(comment 1 "Grand Teton / footprints 3844-3845 of 6105")
	)
	(layers
		(0 "F.Cu" signal "TOP")
		(4 "In1.Cu" signal "GND")
		(6 "In2.Cu" signal "IN1")
		(8 "In3.Cu" signal "GND1")
		(10 "In4.Cu" signal "IN2")
		(12 "In5.Cu" signal "GND2")
		(14 "In6.Cu" signal "IN3")
		(16 "In7.Cu" signal "GND3")
		(18 "In8.Cu" signal "VCC")
		(20 "In9.Cu" signal "VCC1")
		(22 "In10.Cu" signal "GND4")
		(24 "In11.Cu" signal "IN4")
		(26 "In12.Cu" signal "GND5")
		(28 "In13.Cu" signal "IN5")
		(30 "In14.Cu" signal "GND6")
		(32 "In15.Cu" signal "IN6")
		(34 "In16.Cu" signal "GND7")
		(2 "B.Cu" signal "BOTTOM")
		(9 "F.Adhes" user "F.Adhesive")
		(11 "B.Adhes" user "B.Adhesive")
		(13 "F.Paste" user "Package Geometry/Pastemask Top")
		(15 "B.Paste" user "Package Geometry/Pastemask Bottom")
		(5 "F.SilkS" user "Ref Des/Silkscreen Top")
		(7 "B.SilkS" user "Ref Des/Silkscreen Bottom")
		(1 "F.Mask" user "Board Geometry/Soldermask Top")
		(3 "B.Mask" user "Board Geometry/Soldermask Bottom")
		(17 "Dwgs.User" user "User.Drawings")
		(19 "Cmts.User" user "User.Comments")
		(21 "Eco1.User" user "User.Eco1")
		(23 "Eco2.User" user "User.Eco2")
		(25 "Edge.Cuts" user "Board Geometry/Outline")
		(27 "Margin" user)
		(31 "F.CrtYd" user "Package Geometry/Place Bound Top")
		(29 "B.CrtYd" user "Package Geometry/Place Bound Bottom")
		(35 "F.Fab" user "Ref Des/Assembly Top")
		(33 "B.Fab" user "Ref Des/Assembly Bottom")
	)
	(footprint ""
		(layer "F.Cu")
		(at 357.487982 -385.17449 180)
		(property "Reference" "C2271"
			(at 0 0 180)
			(layer "F.SilkS")
			(hide yes)
			(effects
				(font
					(size 1.27 1.27)
				)
			)
		)
		(property "Value" ""
			(at 0 0 180)
			(layer "F.Fab")
			(effects
				(font
					(size 1.27 1.27)
				)
			)
		)
		(duplicate_pad_numbers_are_jumpers no)
		(fp_line
			(start 0.7874 0.4064)
			(end -0.7874 0.4064)
			(stroke
				(width 0.1524)
				(type default)
			)
			(layer "F.SilkS")
		)
		(fp_line
			(start 0.7874 -0.4064)
			(end 0.7874 0.4064)
			(stroke
				(width 0.1524)
				(type default)
			)
			(layer "F.SilkS")
		)
		(fp_line
			(start -0.7874 0.4064)
			(end -0.7874 -0.4064)
			(stroke
				(width 0.1524)
				(type default)
			)
			(layer "F.SilkS")
		)
		(fp_line
			(start -0.7874 -0.4064)
			(end 0.7874 -0.4064)
			(stroke
				(width 0.1524)
				(type default)
			)
			(layer "F.SilkS")
		)
		(fp_line
			(start 0.67945 0.3048)
			(end 0.120396 0.3048)
			(stroke
				(width 0.1)
				(type default)
			)
			(layer "F.Fab")
		)
		(fp_line
			(start 0.67945 -0.3048)
			(end 0.67945 0.3048)
			(stroke
				(width 0.1)
				(type default)
			)
			(layer "F.Fab")
		)
		(fp_line
			(start 0.12065 -0.2794)
			(end 0.12065 -0.3048)
			(stroke
				(width 0.1)
				(type default)
			)
			(layer "F.Fab")
		)
		(fp_line
			(start 0.12065 -0.3048)
			(end 0.67945 -0.3048)
			(stroke
				(width 0.1)
				(type default)
			)
			(layer "F.Fab")
		)
		(fp_line
			(start 0.120396 0.3048)
			(end 0.120396 0.2794)
			(stroke
				(width 0.1)
				(type default)
			)
			(layer "F.Fab")
		)
		(fp_line
			(start 0.120396 0.2794)
			(end -0.12065 0.2794)
			(stroke
				(width 0.1)
				(type default)
			)
			(layer "F.Fab")
		)
		(fp_line
			(start -0.12065 0.3048)
			(end -0.67945 0.3048)
			(stroke
				(width 0.1)
				(type default)
			)
			(layer "F.Fab")
		)
		(fp_line
			(start -0.12065 0.2794)
			(end -0.12065 0.3048)
			(stroke
				(width 0.1)
				(type default)
			)
			(layer "F.Fab")
		)
		(fp_line
			(start -0.12065 -0.2794)
			(end 0.12065 -0.2794)
			(stroke
				(width 0.1)
				(type default)
			)
			(layer "F.Fab")
		)
		(fp_line
			(start -0.12065 -0.305054)
			(end -0.12065 -0.2794)
			(stroke
				(width 0.1)
				(type default)
			)
			(layer "F.Fab")
		)
		(fp_line
			(start -0.67945 0.3048)
			(end -0.67945 -0.305054)
			(stroke
				(width 0.1)
				(type default)
			)
			(layer "F.Fab")
		)
		(fp_line
			(start -0.67945 -0.305054)
			(end -0.12065 -0.305054)
			(stroke
				(width 0.1)
				(type default)
			)
			(layer "F.Fab")
		)
		(pad "1" smd circle
			(at -0.40005 0 180)
			(size 0 0)
			(layers "F.Cu" "F.Mask" "F.Paste")
			(net "GPU_3V3IO_RSVD1_ISO")
		)
		(pad "2" smd circle
			(at 0.40005 0 180)
			(size 0 0)
			(layers "F.Cu" "F.Mask" "F.Paste")
			(net "GND")
		)
	)
	(footprint ""
		(layer "F.Cu")
		(at 261.704582 -71.441056 -90)
		(property "Reference" "PU73"
			(at 0.689864 -2.87274 270)
			(unlocked yes)
			(layer "F.SilkS")
			(effects
				(font
					(size 0.7874 0.5842)
					(thickness 0.1524)
				)
				(justify left)
			)
		)
		(property "Value" ""
			(at 0 0 270)
			(layer "F.Fab")
			(effects
				(font
					(size 1.27 1.27)
				)
			)
		)
		(duplicate_pad_numbers_are_jumpers no)
		(fp_line
			(start -1.549908 2.050034)
			(end -0.5842 2.050034)
			(stroke
				(width 0.1524)
				(type default)
			)
			(layer "F.SilkS")
		)
		(fp_line
			(start 0 2.050034)
			(end 1.549908 2.050034)
			(stroke
				(width 0.1524)
				(type default)
			)
			(layer "F.SilkS")
		)
		(fp_line
			(start 1.549908 2.050034)
			(end 1.549908 1.9304)
			(stroke
				(width 0.1524)
				(type default)
			)
			(layer "F.SilkS")
		)
		(fp_line
			(start -1.549908 1.9812)
			(end -1.549908 2.050034)
			(stroke
				(width 0.1524)
				(type default)
			)
			(layer "F.SilkS")
		)
		(fp_line
			(start 1.549908 -1.9812)
			(end 1.549908 -2.050034)
			(stroke
				(width 0.1524)
				(type default)
			)
			(layer "F.SilkS")
		)
		(fp_line
			(start -1.549908 -2.050034)
			(end -1.549908 -1.9812)
			(stroke
				(width 0.1524)
				(type default)
			)
			(layer "F.SilkS")
		)
		(fp_line
			(start -0.5842 -2.050034)
			(end -1.549908 -2.050034)
			(stroke
				(width 0.1524)
				(type default)
			)
			(layer "F.SilkS")
		)
		(fp_line
			(start 1.549908 -2.050034)
			(end 0.5842 -2.050034)
			(stroke
				(width 0.1524)
				(type default)
			)
			(layer "F.SilkS")
		)
		(fp_poly
			(pts
				(xy -3.273044 -2.227072) (xy -3.273044 -1.211072) (xy -2.257044 -1.719072)
			)
			(stroke
				(width 0)
				(type default)
			)
			(fill yes)
			(layer "F.SilkS")
		)
		(fp_line
			(start -1.549908 2.050034)
			(end 1.549908 2.050034)
			(stroke
				(width 0.1)
				(type default)
			)
			(layer "F.Fab")
		)
		(fp_line
			(start 1.549908 2.050034)
			(end 1.549908 -2.050034)
			(stroke
				(width 0.1)
				(type default)
			)
			(layer "F.Fab")
		)
		(fp_line
			(start -1.549908 -2.050034)
			(end -1.549908 2.050034)
			(stroke
				(width 0.1)
				(type default)
			)
			(layer "F.Fab")
		)
		(fp_line
			(start 1.549908 -2.050034)
			(end -1.549908 -2.050034)
			(stroke
				(width 0.1)
				(type default)
			)
			(layer "F.Fab")
		)
		(fp_poly
			(pts
				(xy -2.9464 -2.208022) (xy -2.9464 -1.192022) (xy -1.9304 -1.700022)
			)
			(stroke
				(width 0)
				(type default)
			)
			(fill yes)
			(layer "F.Fab")
		)
		(pad "1" smd circle
			(at -1.35001 -1.700022 270)
			(size 0 0)
			(layers "F.Cu" "F.Mask" "F.Paste")
			(net "SW_P1V05_PCH_AUX_BST")
		)
		(pad "2" smd rect
			(at -1.400048 -1.199896)
			(size 0.1778 0.8128)
			(layers "F.Cu" "F.Mask" "F.Paste")
			(net "GND")
		)
		(pad "3" smd rect
			(at -1.400048 -0.8001)
			(size 0.1778 0.8128)
			(layers "F.Cu" "F.Mask" "F.Paste")
			(net "P1V05_PCH_AUX_CS")
		)
		(pad "4" smd rect
			(at -1.400048 -0.40005)
			(size 0.1778 0.8128)
			(layers "F.Cu" "F.Mask" "F.Paste")
			(net "P1V05_PCH_AUX_MODE")
		)
		(pad "5" smd rect
			(at -1.400048 0)
			(size 0.1778 0.8128)
			(layers "F.Cu" "F.Mask" "F.Paste")
			(net "P1V05_PCH_AUX_REF")
		)
		(pad "6" smd rect
			(at -1.400048 0.40005)
			(size 0.1778 0.8128)
			(layers "F.Cu" "F.Mask" "F.Paste")
			(net "SH_P1V05_PCH_AUX_N")
		)
		(pad "7" smd rect
			(at -1.400048 0.8001)
			(size 0.1778 0.8128)
			(layers "F.Cu" "F.Mask" "F.Paste")
			(net "P1V05_PCH_AUX_FB")
		)
		(pad "8" smd rect
			(at -1.400048 1.199896)
			(size 0.1778 0.8128)
			(layers "F.Cu" "F.Mask" "F.Paste")
			(net "FM_P1V05_PCH_AUX_R_EN")
		)
		(pad "9" smd rect
			(at -1.400048 1.700022)
			(size 0.3048 0.8128)
			(layers "F.Cu" "F.Mask" "F.Paste")
			(net "PWRGD_P1V05_PCH_AUX_R")
		)
		(pad "10" smd rect
			(at -0.299974 1.299972 270)
			(size 0.3048 2.0066)
			(layers "F.Cu" "F.Mask" "F.Paste")
			(net "SW_P12V_AUX_P1V05_PCH_AUX_FLT")
		)
		(pad "11_18" smd circle
			(at 1.175004 0.275082 270)
			(size 0 0)
			(layers "F.Cu" "F.Mask" "F.Paste")
			(net "GND")
		)
		(pad "19" smd rect
			(at 1.400048 -1.700022 180)
			(size 0.3048 0.8128)
			(layers "F.Cu" "F.Mask" "F.Paste")
			(net "P1V05_PCH_AUX_VCC")
		)
		(pad "20" smd rect
			(at 0.299974 -1.299972 270)
			(size 0.3048 2.0066)
			(layers "F.Cu" "F.Mask" "F.Paste")
			(net "SW_P1V05_PCH_AUX_SW")
		)
		(pad "21" smd rect
			(at -0.299974 -1.299972 270)
			(size 0.3048 2.0066)
			(layers "F.Cu" "F.Mask" "F.Paste")
			(net "SW_P12V_AUX_P1V05_PCH_AUX_FLT")
		)
	)
)
